# T6G (Grand Teton) — schematic netlist excerpt (pin names and nets, part order shuffled) for the footprints in the layout excerpt that follows; sources: Cadence DE-HDL packaged netlist, KiCad conversion of 04192023_DAF0TMB3IC0_F0TG_MB_C_brd_V02_OCP.brd

C406  Q_CAP  4.7UF 6.3V 20% X6S  pkg 0402  page 345 : A = P0V9_CPU1_RT2_2A ; B = GND
C2472  Q_CAP  22UF 4V 20% X6S  pkg C0402  page 74 : A = PVDDCR_SOC_P1 ; B = GND

(kicad_pcb
	(version 20260206)
	(generator "pcbnew")
	(generator_version "10.0")
	(general
		(thickness 1.6)
		(legacy_teardrops no)
	)
	(paper "A4")
	(title_block
		(title "04192023_DAF0TMB3IC0_F0TG_MB_C_brd_V02_OCP.brd")
		(comment 1 "Grand Teton / footprints 6973-6974 of 8354")
	)
	(layers
		(0 "F.Cu" signal "TOP")
		(4 "In1.Cu" signal "GND")
		(6 "In2.Cu" signal "IN1")
		(8 "In3.Cu" signal "GND1")
		(10 "In4.Cu" signal "IN2")
		(12 "In5.Cu" signal "GND2")
		(14 "In6.Cu" signal "IN3")
		(16 "In7.Cu" signal "GND3")
		(18 "In8.Cu" signal "VCC")
		(20 "In9.Cu" signal "VCC1")
		(22 "In10.Cu" signal "GND4")
		(24 "In11.Cu" signal "IN4")
		(26 "In12.Cu" signal "GND5")
		(28 "In13.Cu" signal "IN5")
		(30 "In14.Cu" signal "GND6")
		(32 "In15.Cu" signal "IN6")
		(34 "In16.Cu" signal "GND7")
		(2 "B.Cu" signal "BOTTOM")
		(9 "F.Adhes" user "F.Adhesive")
		(11 "B.Adhes" user "B.Adhesive")
		(13 "F.Paste" user "Package Geometry/Pastemask Top")
		(15 "B.Paste" user "Package Geometry/Pastemask Bottom")
		(5 "F.SilkS" user "Ref Des/Silkscreen Top")
		(7 "B.SilkS" user "Ref Des/Silkscreen Bottom")
		(1 "F.Mask" user "Board Geometry/Soldermask Top")
		(3 "B.Mask" user "Board Geometry/Soldermask Bottom")
		(17 "Dwgs.User" user "User.Drawings")
		(19 "Cmts.User" user "User.Comments")
		(21 "Eco1.User" user "User.Eco1")
		(23 "Eco2.User" user "User.Eco2")
		(25 "Edge.Cuts" user "Board Geometry/Outline")
		(27 "Margin" user)
		(31 "F.CrtYd" user "Package Geometry/Place Bound Top")
		(29 "B.CrtYd" user "Package Geometry/Place Bound Bottom")
		(35 "F.Fab" user "Ref Des/Assembly Top")
		(33 "B.Fab" user "Ref Des/Assembly Bottom")
	)
	(footprint ""
		(layer "B.Cu")
		(at 121.706386 -254.194564)
		(property "Reference" "C2472"
			(at 0 0 0)
			(layer "B.SilkS")
			(hide yes)
			(effects
				(font
					(size 1.27 1.27)
				)
				(justify mirror)
			)
		)
		(property "Value" ""
			(at 0 0 0)
			(layer "B.Fab")
			(effects
				(font
					(size 1.27 1.27)
				)
				(justify mirror)
			)
		)
		(duplicate_pad_numbers_are_jumpers no)
		(fp_line
			(start -0.7874 -0.4064)
			(end -0.7874 0.4064)
			(stroke
				(width 0.1524)
				(type default)
			)
			(layer "B.SilkS")
		)
		(fp_line
			(start -0.7874 0.4064)
			(end 0.7874 0.4064)
			(stroke
				(width 0.1524)
				(type default)
			)
			(layer "B.SilkS")
		)
		(fp_line
			(start 0.7874 -0.4064)
			(end -0.7874 -0.4064)
			(stroke
				(width 0.1524)
				(type default)
			)
			(layer "B.SilkS")
		)
		(fp_line
			(start 0.7874 0.4064)
			(end 0.7874 -0.4064)
			(stroke
				(width 0.1524)
				(type default)
			)
			(layer "B.SilkS")
		)
		(fp_line
			(start -0.67945 -0.3048)
			(end -0.67945 0.3048)
			(stroke
				(width 0.1)
				(type default)
			)
			(layer "B.Fab")
		)
		(fp_line
			(start -0.67945 0.3048)
			(end -0.120396 0.3048)
			(stroke
				(width 0.1)
				(type default)
			)
			(layer "B.Fab")
		)
		(fp_line
			(start -0.12065 -0.3048)
			(end -0.67945 -0.3048)
			(stroke
				(width 0.1)
				(type default)
			)
			(layer "B.Fab")
		)
		(fp_line
			(start -0.12065 -0.2794)
			(end -0.12065 -0.3048)
			(stroke
				(width 0.1)
				(type default)
			)
			(layer "B.Fab")
		)
		(fp_line
			(start -0.120396 0.2794)
			(end 0.12065 0.2794)
			(stroke
				(width 0.1)
				(type default)
			)
			(layer "B.Fab")
		)
		(fp_line
			(start -0.120396 0.3048)
			(end -0.120396 0.2794)
			(stroke
				(width 0.1)
				(type default)
			)
			(layer "B.Fab")
		)
		(fp_line
			(start 0.12065 -0.305054)
			(end 0.12065 -0.2794)
			(stroke
				(width 0.1)
				(type default)
			)
			(layer "B.Fab")
		)
		(fp_line
			(start 0.12065 -0.2794)
			(end -0.12065 -0.2794)
			(stroke
				(width 0.1)
				(type default)
			)
			(layer "B.Fab")
		)
		(fp_line
			(start 0.12065 0.2794)
			(end 0.12065 0.3048)
			(stroke
				(width 0.1)
				(type default)
			)
			(layer "B.Fab")
		)
		(fp_line
			(start 0.12065 0.3048)
			(end 0.67945 0.3048)
			(stroke
				(width 0.1)
				(type default)
			)
			(layer "B.Fab")
		)
		(fp_line
			(start 0.67945 -0.305054)
			(end 0.12065 -0.305054)
			(stroke
				(width 0.1)
				(type default)
			)
			(layer "B.Fab")
		)
		(fp_line
			(start 0.67945 0.3048)
			(end 0.67945 -0.305054)
			(stroke
				(width 0.1)
				(type default)
			)
			(layer "B.Fab")
		)
		(pad "1" smd circle
			(at 0.40005 0 180)
			(size 0 0)
			(layers "B.Cu" "B.Mask" "B.Paste")
			(net "PVDDCR_SOC_P1")
		)
		(pad "2" smd circle
			(at -0.40005 0 180)
			(size 0 0)
			(layers "B.Cu" "B.Mask" "B.Paste")
			(net "GND")
		)
	)
	(footprint ""
		(layer "B.Cu")
		(at 149.419056 -390.560052 90)
		(property "Reference" "C406"
			(at 0 0 90)
			(layer "B.SilkS")
			(hide yes)
			(effects
				(font
					(size 1.27 1.27)
				)
				(justify mirror)
			)
		)
		(property "Value" ""
			(at 0 0 90)
			(layer "B.Fab")
			(effects
				(font
					(size 1.27 1.27)
				)
				(justify mirror)
			)
		)
		(duplicate_pad_numbers_are_jumpers no)
		(fp_line
			(start 0.7874 -0.4064)
			(end -0.7874 -0.4064)
			(stroke
				(width 0.1524)
				(type default)
			)
			(layer "B.SilkS")
		)
		(fp_line
			(start -0.7874 -0.4064)
			(end -0.7874 0.4064)
			(stroke
				(width 0.1524)
				(type default)
			)
			(layer "B.SilkS")
		)
		(fp_line
			(start 0.7874 0.4064)
			(end 0.7874 -0.4064)
			(stroke
				(width 0.1524)
				(type default)
			)
			(layer "B.SilkS")
		)
		(fp_line
			(start -0.7874 0.4064)
			(end 0.7874 0.4064)
			(stroke
				(width 0.1524)
				(type default)
			)
			(layer "B.SilkS")
		)
		(fp_line
			(start 0.67945 -0.305054)
			(end 0.12065 -0.305054)
			(stroke
				(width 0.1)
				(type default)
			)
			(layer "B.Fab")
		)
		(fp_line
			(start 0.12065 -0.305054)
			(end 0.12065 -0.2794)
			(stroke
				(width 0.1)
				(type default)
			)
			(layer "B.Fab")
		)
		(fp_line
			(start -0.12065 -0.3048)
			(end -0.67945 -0.3048)
			(stroke
				(width 0.1)
				(type default)
			)
			(layer "B.Fab")
		)
		(fp_line
			(start -0.67945 -0.3048)
			(end -0.67945 0.3048)
			(stroke
				(width 0.1)
				(type default)
			)
			(layer "B.Fab")
		)
		(fp_line
			(start 0.12065 -0.2794)
			(end -0.12065 -0.2794)
			(stroke
				(width 0.1)
				(type default)
			)
			(layer "B.Fab")
		)
		(fp_line
			(start -0.12065 -0.2794)
			(end -0.12065 -0.3048)
			(stroke
				(width 0.1)
				(type default)
			)
			(layer "B.Fab")
		)
		(fp_line
			(start 0.12065 0.2794)
			(end 0.12065 0.3048)
			(stroke
				(width 0.1)
				(type default)
			)
			(layer "B.Fab")
		)
		(fp_line
			(start -0.120396 0.2794)
			(end 0.12065 0.2794)
			(stroke
				(width 0.1)
				(type default)
			)
			(layer "B.Fab")
		)
		(fp_line
			(start 0.67945 0.3048)
			(end 0.67945 -0.305054)
			(stroke
				(width 0.1)
				(type default)
			)
			(layer "B.Fab")
		)
		(fp_line
			(start 0.12065 0.3048)
			(end 0.67945 0.3048)
			(stroke
				(width 0.1)
				(type default)
			)
			(layer "B.Fab")
		)
		(fp_line
			(start -0.120396 0.3048)
			(end -0.120396 0.2794)
			(stroke
				(width 0.1)
				(type default)
			)
			(layer "B.Fab")
		)
		(fp_line
			(start -0.67945 0.3048)
			(end -0.120396 0.3048)
			(stroke
				(width 0.1)
				(type default)
			)
			(layer "B.Fab")
		)
		(pad "1" smd circle
			(at 0.40005 0 270)
			(size 0 0)
			(layers "B.Cu" "B.Mask" "B.Paste")
			(net "P0V9_CPU1_RT2_2A")
		)
		(pad "2" smd circle
			(at -0.40005 0 270)
			(size 0 0)
			(layers "B.Cu" "B.Mask" "B.Paste")
			(net "GND")
		)
	)
)
